(kicad_pcb
	(version 20260206)
	(generator "pcbnew")
	(generator_version "10.0")
	(general
		(thickness 1.6)
		(legacy_teardrops no)
	)
	(paper "A4")
	(title_block
		(title "01162023_DA0F0TEBIF0_F0T_Expander_BD_F_brd_V02_OCP.brd")
		(comment 1 "Grand Teton / footprints 7050-7055 of 9728")
	)
	(layers
		(0 "F.Cu" signal "TOP")
		(4 "In1.Cu" signal "GND")
		(6 "In2.Cu" signal "VCC")
		(8 "In3.Cu" signal "VCC1")
		(10 "In4.Cu" signal "GND1")
		(12 "In5.Cu" signal "IN1")
		(14 "In6.Cu" signal "GND2")
		(16 "In7.Cu" signal "IN2")
		(18 "In8.Cu" signal "GND3")
		(20 "In9.Cu" signal "IN3")
		(22 "In10.Cu" signal "GND4")
		(24 "In11.Cu" signal "IN4")
		(26 "In12.Cu" signal "GND5")
		(28 "In13.Cu" signal "IN5")
		(30 "In14.Cu" signal "GND6")
		(32 "In15.Cu" signal "IN6")
		(34 "In16.Cu" signal "GND7")
		(2 "B.Cu" signal "BOTTOM")
		(9 "F.Adhes" user "F.Adhesive")
		(11 "B.Adhes" user "B.Adhesive")
		(13 "F.Paste" user "Package Geometry/Pastemask Top")
		(15 "B.Paste" user "Package Geometry/Pastemask Bottom")
		(5 "F.SilkS" user "Ref Des/Silkscreen Top")
		(7 "B.SilkS" user "Ref Des/Silkscreen Bottom")
		(1 "F.Mask" user "Board Geometry/Soldermask Top")
		(3 "B.Mask" user "Board Geometry/Soldermask Bottom")
		(17 "Dwgs.User" user "User.Drawings")
		(19 "Cmts.User" user "User.Comments")
		(21 "Eco1.User" user "User.Eco1")
		(23 "Eco2.User" user "User.Eco2")
		(25 "Edge.Cuts" user "Board Geometry/Outline")
		(27 "Margin" user)
		(31 "F.CrtYd" user "Package Geometry/Place Bound Top")
		(29 "B.CrtYd" user "Package Geometry/Place Bound Bottom")
		(35 "F.Fab" user "Ref Des/Assembly Top")
		(33 "B.Fab" user "Ref Des/Assembly Bottom")
	)
	(footprint ""
		(layer "F.Cu")
		(at 289.856164 -61.487812 180)
		(property "Reference" "R6002"
			(at 0 0 180)
			(layer "F.SilkS")
			(hide yes)
			(effects
				(font
					(size 1.27 1.27)
				)
			)
		)
		(property "Value" ""
			(at 0 0 180)
			(layer "F.Fab")
			(effects
				(font
					(size 1.27 1.27)
				)
			)
		)
		(duplicate_pad_numbers_are_jumpers no)
		(fp_line
			(start 0.7874 0.4064)
			(end -0.7874 0.4064)
			(stroke
				(width 0.1524)
				(type default)
			)
			(layer "F.SilkS")
		)
		(fp_line
			(start 0.7874 -0.4064)
			(end 0.7874 0.4064)
			(stroke
				(width 0.1524)
				(type default)
			)
			(layer "F.SilkS")
		)
		(fp_line
			(start -0.7874 0.4064)
			(end -0.7874 -0.4064)
			(stroke
				(width 0.1524)
				(type default)
			)
			(layer "F.SilkS")
		)
		(fp_line
			(start -0.7874 -0.4064)
			(end 0.7874 -0.4064)
			(stroke
				(width 0.1524)
				(type default)
			)
			(layer "F.SilkS")
		)
		(fp_line
			(start 0.67945 0.3048)
			(end 0.120396 0.3048)
			(stroke
				(width 0.1)
				(type default)
			)
			(layer "F.Fab")
		)
		(fp_line
			(start 0.67945 -0.3048)
			(end 0.67945 0.3048)
			(stroke
				(width 0.1)
				(type default)
			)
			(layer "F.Fab")
		)
		(fp_line
			(start 0.12065 -0.2794)
			(end 0.12065 -0.3048)
			(stroke
				(width 0.1)
				(type default)
			)
			(layer "F.Fab")
		)
		(fp_line
			(start 0.12065 -0.3048)
			(end 0.67945 -0.3048)
			(stroke
				(width 0.1)
				(type default)
			)
			(layer "F.Fab")
		)
		(fp_line
			(start 0.120396 0.3048)
			(end 0.120396 0.2794)
			(stroke
				(width 0.1)
				(type default)
			)
			(layer "F.Fab")
		)
		(fp_line
			(start 0.120396 0.2794)
			(end -0.12065 0.2794)
			(stroke
				(width 0.1)
				(type default)
			)
			(layer "F.Fab")
		)
		(fp_line
			(start -0.12065 0.3048)
			(end -0.67945 0.3048)
			(stroke
				(width 0.1)
				(type default)
			)
			(layer "F.Fab")
		)
		(fp_line
			(start -0.12065 0.2794)
			(end -0.12065 0.3048)
			(stroke
				(width 0.1)
				(type default)
			)
			(layer "F.Fab")
		)
		(fp_line
			(start -0.12065 -0.2794)
			(end 0.12065 -0.2794)
			(stroke
				(width 0.1)
				(type default)
			)
			(layer "F.Fab")
		)
		(fp_line
			(start -0.12065 -0.305054)
			(end -0.12065 -0.2794)
			(stroke
				(width 0.1)
				(type default)
			)
			(layer "F.Fab")
		)
		(fp_line
			(start -0.67945 0.3048)
			(end -0.67945 -0.305054)
			(stroke
				(width 0.1)
				(type default)
			)
			(layer "F.Fab")
		)
		(fp_line
			(start -0.67945 -0.305054)
			(end -0.12065 -0.305054)
			(stroke
				(width 0.1)
				(type default)
			)
			(layer "F.Fab")
		)
		(pad "1" smd circle
			(at -0.40005 0 180)
			(size 0 0)
			(layers "F.Cu" "F.Mask" "F.Paste")
			(net "P3V3_AUX")
		)
		(pad "2" smd circle
			(at 0.40005 0 180)
			(size 0 0)
			(layers "F.Cu" "F.Mask" "F.Paste")
			(net "PWRGD_P12V_SSD10_D")
		)
	)
	(footprint ""
		(layer "F.Cu")
		(at 72.7202 -229.289356 90)
		(property "Reference" "R6638"
			(at 0 0 90)
			(layer "F.SilkS")
			(hide yes)
			(effects
				(font
					(size 1.27 1.27)
				)
			)
		)
		(property "Value" ""
			(at 0 0 90)
			(layer "F.Fab")
			(effects
				(font
					(size 1.27 1.27)
				)
			)
		)
		(duplicate_pad_numbers_are_jumpers no)
		(fp_line
			(start 0.7874 -0.4064)
			(end 0.7874 0.4064)
			(stroke
				(width 0.1524)
				(type default)
			)
			(layer "F.SilkS")
		)
		(fp_line
			(start -0.7874 -0.4064)
			(end 0.7874 -0.4064)
			(stroke
				(width 0.1524)
				(type default)
			)
			(layer "F.SilkS")
		)
		(fp_line
			(start 0.7874 0.4064)
			(end -0.7874 0.4064)
			(stroke
				(width 0.1524)
				(type default)
			)
			(layer "F.SilkS")
		)
		(fp_line
			(start -0.7874 0.4064)
			(end -0.7874 -0.4064)
			(stroke
				(width 0.1524)
				(type default)
			)
			(layer "F.SilkS")
		)
		(fp_line
			(start -0.12065 -0.305054)
			(end -0.12065 -0.2794)
			(stroke
				(width 0.1)
				(type default)
			)
			(layer "F.Fab")
		)
		(fp_line
			(start -0.67945 -0.305054)
			(end -0.12065 -0.305054)
			(stroke
				(width 0.1)
				(type default)
			)
			(layer "F.Fab")
		)
		(fp_line
			(start 0.67945 -0.3048)
			(end 0.67945 0.3048)
			(stroke
				(width 0.1)
				(type default)
			)
			(layer "F.Fab")
		)
		(fp_line
			(start 0.12065 -0.3048)
			(end 0.67945 -0.3048)
			(stroke
				(width 0.1)
				(type default)
			)
			(layer "F.Fab")
		)
		(fp_line
			(start 0.12065 -0.2794)
			(end 0.12065 -0.3048)
			(stroke
				(width 0.1)
				(type default)
			)
			(layer "F.Fab")
		)
		(fp_line
			(start -0.12065 -0.2794)
			(end 0.12065 -0.2794)
			(stroke
				(width 0.1)
				(type default)
			)
			(layer "F.Fab")
		)
		(fp_line
			(start 0.120396 0.2794)
			(end -0.12065 0.2794)
			(stroke
				(width 0.1)
				(type default)
			)
			(layer "F.Fab")
		)
		(fp_line
			(start -0.12065 0.2794)
			(end -0.12065 0.3048)
			(stroke
				(width 0.1)
				(type default)
			)
			(layer "F.Fab")
		)
		(fp_line
			(start 0.67945 0.3048)
			(end 0.120396 0.3048)
			(stroke
				(width 0.1)
				(type default)
			)
			(layer "F.Fab")
		)
		(fp_line
			(start 0.120396 0.3048)
			(end 0.120396 0.2794)
			(stroke
				(width 0.1)
				(type default)
			)
			(layer "F.Fab")
		)
		(fp_line
			(start -0.12065 0.3048)
			(end -0.67945 0.3048)
			(stroke
				(width 0.1)
				(type default)
			)
			(layer "F.Fab")
		)
		(fp_line
			(start -0.67945 0.3048)
			(end -0.67945 -0.305054)
			(stroke
				(width 0.1)
				(type default)
			)
			(layer "F.Fab")
		)
		(pad "1" smd circle
			(at -0.40005 0 90)
			(size 0 0)
			(layers "F.Cu" "F.Mask" "F.Paste")
			(net "UART_PEX1_CLI_BUF_R_TX")
		)
		(pad "2" smd circle
			(at 0.40005 0 90)
			(size 0 0)
			(layers "F.Cu" "F.Mask" "F.Paste")
			(net "UART_PEX1_CLI_BUF_R1_TX")
		)
	)
	(footprint ""
		(layer "F.Cu")
		(at 351.65792 -27.006296 -90)
		(property "Reference" "PR7123"
			(at 0 0 270)
			(layer "F.SilkS")
			(hide yes)
			(effects
				(font
					(size 1.27 1.27)
				)
			)
		)
		(property "Value" ""
			(at 0 0 270)
			(layer "F.Fab")
			(effects
				(font
					(size 1.27 1.27)
				)
			)
		)
		(duplicate_pad_numbers_are_jumpers no)
		(fp_line
			(start -0.7874 0.4064)
			(end -0.7874 -0.4064)
			(stroke
				(width 0.1524)
				(type default)
			)
			(layer "F.SilkS")
		)
		(fp_line
			(start 0.7874 0.4064)
			(end -0.7874 0.4064)
			(stroke
				(width 0.1524)
				(type default)
			)
			(layer "F.SilkS")
		)
		(fp_line
			(start -0.7874 -0.4064)
			(end 0.7874 -0.4064)
			(stroke
				(width 0.1524)
				(type default)
			)
			(layer "F.SilkS")
		)
		(fp_line
			(start 0.7874 -0.4064)
			(end 0.7874 0.4064)
			(stroke
				(width 0.1524)
				(type default)
			)
			(layer "F.SilkS")
		)
		(fp_line
			(start -0.67945 0.3048)
			(end -0.67945 -0.305054)
			(stroke
				(width 0.1)
				(type default)
			)
			(layer "F.Fab")
		)
		(fp_line
			(start -0.12065 0.3048)
			(end -0.67945 0.3048)
			(stroke
				(width 0.1)
				(type default)
			)
			(layer "F.Fab")
		)
		(fp_line
			(start 0.120396 0.3048)
			(end 0.120396 0.2794)
			(stroke
				(width 0.1)
				(type default)
			)
			(layer "F.Fab")
		)
		(fp_line
			(start 0.67945 0.3048)
			(end 0.120396 0.3048)
			(stroke
				(width 0.1)
				(type default)
			)
			(layer "F.Fab")
		)
		(fp_line
			(start -0.12065 0.2794)
			(end -0.12065 0.3048)
			(stroke
				(width 0.1)
				(type default)
			)
			(layer "F.Fab")
		)
		(fp_line
			(start 0.120396 0.2794)
			(end -0.12065 0.2794)
			(stroke
				(width 0.1)
				(type default)
			)
			(layer "F.Fab")
		)
		(fp_line
			(start -0.12065 -0.2794)
			(end 0.12065 -0.2794)
			(stroke
				(width 0.1)
				(type default)
			)
			(layer "F.Fab")
		)
		(fp_line
			(start 0.12065 -0.2794)
			(end 0.12065 -0.3048)
			(stroke
				(width 0.1)
				(type default)
			)
			(layer "F.Fab")
		)
		(fp_line
			(start 0.12065 -0.3048)
			(end 0.67945 -0.3048)
			(stroke
				(width 0.1)
				(type default)
			)
			(layer "F.Fab")
		)
		(fp_line
			(start 0.67945 -0.3048)
			(end 0.67945 0.3048)
			(stroke
				(width 0.1)
				(type default)
			)
			(layer "F.Fab")
		)
		(fp_line
			(start -0.67945 -0.305054)
			(end -0.12065 -0.305054)
			(stroke
				(width 0.1)
				(type default)
			)
			(layer "F.Fab")
		)
		(fp_line
			(start -0.12065 -0.305054)
			(end -0.12065 -0.2794)
			(stroke
				(width 0.1)
				(type default)
			)
			(layer "F.Fab")
		)
		(pad "1" smd circle
			(at -0.40005 0 270)
			(size 0 0)
			(layers "F.Cu" "F.Mask" "F.Paste")
			(net "P3V3_SSD12_CO_MODE")
		)
		(pad "2" smd circle
			(at 0.40005 0 270)
			(size 0 0)
			(layers "F.Cu" "F.Mask" "F.Paste")
			(net "GND")
		)
	)
	(footprint ""
		(layer "F.Cu")
		(at 407.295096 -98.734372)
		(property "Reference" "R358"
			(at 0 0 0)
			(layer "F.SilkS")
			(hide yes)
			(effects
				(font
					(size 1.27 1.27)
				)
			)
		)
		(property "Value" ""
			(at 0 0 0)
			(layer "F.Fab")
			(effects
				(font
					(size 1.27 1.27)
				)
			)
		)
		(duplicate_pad_numbers_are_jumpers no)
		(fp_line
			(start -0.7874 -0.4064)
			(end 0.7874 -0.4064)
			(stroke
				(width 0.1524)
				(type default)
			)
			(layer "F.SilkS")
		)
		(fp_line
			(start -0.7874 0.4064)
			(end -0.7874 -0.4064)
			(stroke
				(width 0.1524)
				(type default)
			)
			(layer "F.SilkS")
		)
		(fp_line
			(start 0.7874 -0.4064)
			(end 0.7874 0.4064)
			(stroke
				(width 0.1524)
				(type default)
			)
			(layer "F.SilkS")
		)
		(fp_line
			(start 0.7874 0.4064)
			(end -0.7874 0.4064)
			(stroke
				(width 0.1524)
				(type default)
			)
			(layer "F.SilkS")
		)
		(fp_line
			(start -0.67945 -0.305054)
			(end -0.12065 -0.305054)
			(stroke
				(width 0.1)
				(type default)
			)
			(layer "F.Fab")
		)
		(fp_line
			(start -0.67945 0.3048)
			(end -0.67945 -0.305054)
			(stroke
				(width 0.1)
				(type default)
			)
			(layer "F.Fab")
		)
		(fp_line
			(start -0.12065 -0.305054)
			(end -0.12065 -0.2794)
			(stroke
				(width 0.1)
				(type default)
			)
			(layer "F.Fab")
		)
		(fp_line
			(start -0.12065 -0.2794)
			(end 0.12065 -0.2794)
			(stroke
				(width 0.1)
				(type default)
			)
			(layer "F.Fab")
		)
		(fp_line
			(start -0.12065 0.2794)
			(end -0.12065 0.3048)
			(stroke
				(width 0.1)
				(type default)
			)
			(layer "F.Fab")
		)
		(fp_line
			(start -0.12065 0.3048)
			(end -0.67945 0.3048)
			(stroke
				(width 0.1)
				(type default)
			)
			(layer "F.Fab")
		)
		(fp_line
			(start 0.120396 0.2794)
			(end -0.12065 0.2794)
			(stroke
				(width 0.1)
				(type default)
			)
			(layer "F.Fab")
		)
		(fp_line
			(start 0.120396 0.3048)
			(end 0.120396 0.2794)
			(stroke
				(width 0.1)
				(type default)
			)
			(layer "F.Fab")
		)
		(fp_line
			(start 0.12065 -0.3048)
			(end 0.67945 -0.3048)
			(stroke
				(width 0.1)
				(type default)
			)
			(layer "F.Fab")
		)
		(fp_line
			(start 0.12065 -0.2794)
			(end 0.12065 -0.3048)
			(stroke
				(width 0.1)
				(type default)
			)
			(layer "F.Fab")
		)
		(fp_line
			(start 0.67945 -0.3048)
			(end 0.67945 0.3048)
			(stroke
				(width 0.1)
				(type default)
			)
			(layer "F.Fab")
		)
		(fp_line
			(start 0.67945 0.3048)
			(end 0.120396 0.3048)
			(stroke
				(width 0.1)
				(type default)
			)
			(layer "F.Fab")
		)
		(pad "1" smd circle
			(at -0.40005 0)
			(size 0 0)
			(layers "F.Cu" "F.Mask" "F.Paste")
			(net "NIC7_RBT_ARB_OUT")
		)
		(pad "2" smd circle
			(at 0.40005 0)
			(size 0 0)
			(layers "F.Cu" "F.Mask" "F.Paste")
			(net "NIC7_RBT_ARB_IN")
		)
	)
	(footprint ""
		(layer "F.Cu")
		(at 254.177292 -77.279754 -90)
		(property "Reference" "R1056"
			(at 0 0 270)
			(layer "F.SilkS")
			(hide yes)
			(effects
				(font
					(size 1.27 1.27)
				)
			)
		)
		(property "Value" ""
			(at 0 0 270)
			(layer "F.Fab")
			(effects
				(font
					(size 1.27 1.27)
				)
			)
		)
		(duplicate_pad_numbers_are_jumpers no)
		(fp_line
			(start -0.7874 0.4064)
			(end -0.7874 -0.4064)
			(stroke
				(width 0.1524)
				(type default)
			)
			(layer "F.SilkS")
		)
		(fp_line
			(start 0.7874 0.4064)
			(end -0.7874 0.4064)
			(stroke
				(width 0.1524)
				(type default)
			)
			(layer "F.SilkS")
		)
		(fp_line
			(start -0.7874 -0.4064)
			(end 0.7874 -0.4064)
			(stroke
				(width 0.1524)
				(type default)
			)
			(layer "F.SilkS")
		)
		(fp_line
			(start 0.7874 -0.4064)
			(end 0.7874 0.4064)
			(stroke
				(width 0.1524)
				(type default)
			)
			(layer "F.SilkS")
		)
		(fp_line
			(start -0.67945 0.3048)
			(end -0.67945 -0.305054)
			(stroke
				(width 0.1)
				(type default)
			)
			(layer "F.Fab")
		)
		(fp_line
			(start -0.12065 0.3048)
			(end -0.67945 0.3048)
			(stroke
				(width 0.1)
				(type default)
			)
			(layer "F.Fab")
		)
		(fp_line
			(start 0.120396 0.3048)
			(end 0.120396 0.2794)
			(stroke
				(width 0.1)
				(type default)
			)
			(layer "F.Fab")
		)
		(fp_line
			(start 0.67945 0.3048)
			(end 0.120396 0.3048)
			(stroke
				(width 0.1)
				(type default)
			)
			(layer "F.Fab")
		)
		(fp_line
			(start -0.12065 0.2794)
			(end -0.12065 0.3048)
			(stroke
				(width 0.1)
				(type default)
			)
			(layer "F.Fab")
		)
		(fp_line
			(start 0.120396 0.2794)
			(end -0.12065 0.2794)
			(stroke
				(width 0.1)
				(type default)
			)
			(layer "F.Fab")
		)
		(fp_line
			(start -0.12065 -0.2794)
			(end 0.12065 -0.2794)
			(stroke
				(width 0.1)
				(type default)
			)
			(layer "F.Fab")
		)
		(fp_line
			(start 0.12065 -0.2794)
			(end 0.12065 -0.3048)
			(stroke
				(width 0.1)
				(type default)
			)
			(layer "F.Fab")
		)
		(fp_line
			(start 0.12065 -0.3048)
			(end 0.67945 -0.3048)
			(stroke
				(width 0.1)
				(type default)
			)
			(layer "F.Fab")
		)
		(fp_line
			(start 0.67945 -0.3048)
			(end 0.67945 0.3048)
			(stroke
				(width 0.1)
				(type default)
			)
			(layer "F.Fab")
		)
		(fp_line
			(start -0.67945 -0.305054)
			(end -0.12065 -0.305054)
			(stroke
				(width 0.1)
				(type default)
			)
			(layer "F.Fab")
		)
		(fp_line
			(start -0.12065 -0.305054)
			(end -0.12065 -0.2794)
			(stroke
				(width 0.1)
				(type default)
			)
			(layer "F.Fab")
		)
		(pad "1" smd circle
			(at -0.40005 0 270)
			(size 0 0)
			(layers "F.Cu" "F.Mask" "F.Paste")
			(net "FM_CLK_CK440_SS_EN")
		)
		(pad "2" smd circle
			(at 0.40005 0 270)
			(size 0 0)
			(layers "F.Cu" "F.Mask" "F.Paste")
			(net "P3V3")
		)
	)
	(footprint ""
		(layer "F.Cu")
		(at 432.418998 -59.574684 90)
		(property "Reference" "PC433"
			(at 0 0 90)
			(layer "F.SilkS")
			(hide yes)
			(effects
				(font
					(size 1.27 1.27)
				)
			)
		)
		(property "Value" ""
			(at 0 0 90)
			(layer "F.Fab")
			(effects
				(font
					(size 1.27 1.27)
				)
			)
		)
		(duplicate_pad_numbers_are_jumpers no)
		(fp_line
			(start 0.7874 -0.4064)
			(end 0.7874 0.4064)
			(stroke
				(width 0.1524)
				(type default)
			)
			(layer "F.SilkS")
		)
		(fp_line
			(start -0.7874 -0.4064)
			(end 0.7874 -0.4064)
			(stroke
				(width 0.1524)
				(type default)
			)
			(layer "F.SilkS")
		)
		(fp_line
			(start 0.7874 0.4064)
			(end -0.7874 0.4064)
			(stroke
				(width 0.1524)
				(type default)
			)
			(layer "F.SilkS")
		)
		(fp_line
			(start -0.7874 0.4064)
			(end -0.7874 -0.4064)
			(stroke
				(width 0.1524)
				(type default)
			)
			(layer "F.SilkS")
		)
		(fp_line
			(start -0.12065 -0.305054)
			(end -0.12065 -0.2794)
			(stroke
				(width 0.1)
				(type default)
			)
			(layer "F.Fab")
		)
		(fp_line
			(start -0.67945 -0.305054)
			(end -0.12065 -0.305054)
			(stroke
				(width 0.1)
				(type default)
			)
			(layer "F.Fab")
		)
		(fp_line
			(start 0.67945 -0.3048)
			(end 0.67945 0.3048)
			(stroke
				(width 0.1)
				(type default)
			)
			(layer "F.Fab")
		)
		(fp_line
			(start 0.12065 -0.3048)
			(end 0.67945 -0.3048)
			(stroke
				(width 0.1)
				(type default)
			)
			(layer "F.Fab")
		)
		(fp_line
			(start 0.12065 -0.2794)
			(end 0.12065 -0.3048)
			(stroke
				(width 0.1)
				(type default)
			)
			(layer "F.Fab")
		)
		(fp_line
			(start -0.12065 -0.2794)
			(end 0.12065 -0.2794)
			(stroke
				(width 0.1)
				(type default)
			)
			(layer "F.Fab")
		)
		(fp_line
			(start 0.120396 0.2794)
			(end -0.12065 0.2794)
			(stroke
				(width 0.1)
				(type default)
			)
			(layer "F.Fab")
		)
		(fp_line
			(start -0.12065 0.2794)
			(end -0.12065 0.3048)
			(stroke
				(width 0.1)
				(type default)
			)
			(layer "F.Fab")
		)
		(fp_line
			(start 0.67945 0.3048)
			(end 0.120396 0.3048)
			(stroke
				(width 0.1)
				(type default)
			)
			(layer "F.Fab")
		)
		(fp_line
			(start 0.120396 0.3048)
			(end 0.120396 0.2794)
			(stroke
				(width 0.1)
				(type default)
			)
			(layer "F.Fab")
		)
		(fp_line
			(start -0.12065 0.3048)
			(end -0.67945 0.3048)
			(stroke
				(width 0.1)
				(type default)
			)
			(layer "F.Fab")
		)
		(fp_line
			(start -0.67945 0.3048)
			(end -0.67945 -0.305054)
			(stroke
				(width 0.1)
				(type default)
			)
			(layer "F.Fab")
		)
		(pad "1" smd circle
			(at -0.40005 0 90)
			(size 0 0)
			(layers "F.Cu" "F.Mask" "F.Paste")
			(net "P5V_AUX")
		)
		(pad "2" smd circle
			(at 0.40005 0 90)
			(size 0 0)
			(layers "F.Cu" "F.Mask" "F.Paste")
			(net "GND")
		)
	)
)
